# T6G (Grand Teton) — schematic netlist excerpt (pin names and nets, part order shuffled) for the footprints in the layout excerpt that follows; sources: Cadence DE-HDL packaged netlist, KiCad conversion of 04192023_DAF0TMB3IC0_F0TG_MB_C_brd_V02_OCP.brd

C848  Q_CAP_DIFFBUS  DIFF BUS_0.22UF 6.3V 20% X6S  pkg C0201  page 64 : \1\ = P5E_CPU0_P2_TX_C_DN<10> ; \2\ = P5E_CPU0_P2_TX_DN<10>
PR263  Q_RES  8.87K 1% EMPTY  pkg 0402LF  page 219 : A = PVDDCR_CPU1_P1_LSET3 ; B = GND
C2641  Q_CAP  22UF 4V 20% X6S  pkg C0402  page 70 : A = PVDD11_S3_P0 ; B = GND

(kicad_pcb
	(version 20260206)
	(generator "pcbnew")
	(generator_version "10.0")
	(general
		(thickness 1.6)
		(legacy_teardrops no)
	)
	(paper "A4")
	(title_block
		(title "04192023_DAF0TMB3IC0_F0TG_MB_C_brd_V02_OCP.brd")
		(comment 1 "Grand Teton / footprints 300-302 of 8354")
	)
	(layers
		(0 "F.Cu" signal "TOP")
		(4 "In1.Cu" signal "GND")
		(6 "In2.Cu" signal "IN1")
		(8 "In3.Cu" signal "GND1")
		(10 "In4.Cu" signal "IN2")
		(12 "In5.Cu" signal "GND2")
		(14 "In6.Cu" signal "IN3")
		(16 "In7.Cu" signal "GND3")
		(18 "In8.Cu" signal "VCC")
		(20 "In9.Cu" signal "VCC1")
		(22 "In10.Cu" signal "GND4")
		(24 "In11.Cu" signal "IN4")
		(26 "In12.Cu" signal "GND5")
		(28 "In13.Cu" signal "IN5")
		(30 "In14.Cu" signal "GND6")
		(32 "In15.Cu" signal "IN6")
		(34 "In16.Cu" signal "GND7")
		(2 "B.Cu" signal "BOTTOM")
		(9 "F.Adhes" user "F.Adhesive")
		(11 "B.Adhes" user "B.Adhesive")
		(13 "F.Paste" user "Package Geometry/Pastemask Top")
		(15 "B.Paste" user "Package Geometry/Pastemask Bottom")
		(5 "F.SilkS" user "Ref Des/Silkscreen Top")
		(7 "B.SilkS" user "Ref Des/Silkscreen Bottom")
		(1 "F.Mask" user "Board Geometry/Soldermask Top")
		(3 "B.Mask" user "Board Geometry/Soldermask Bottom")
		(17 "Dwgs.User" user "User.Drawings")
		(19 "Cmts.User" user "User.Comments")
		(21 "Eco1.User" user "User.Eco1")
		(23 "Eco2.User" user "User.Eco2")
		(25 "Edge.Cuts" user "Board Geometry/Outline")
		(27 "Margin" user)
		(31 "F.CrtYd" user "Package Geometry/Place Bound Top")
		(29 "B.CrtYd" user "Package Geometry/Place Bound Bottom")
		(35 "F.Fab" user "Ref Des/Assembly Top")
		(33 "B.Fab" user "Ref Des/Assembly Bottom")
	)
	(footprint ""
		(layer "F.Cu")
		(at 69.10451 -340.211664)
		(property "Reference" "PR263"
			(at 0 0 0)
			(layer "F.SilkS")
			(hide yes)
			(effects
				(font
					(size 1.27 1.27)
				)
			)
		)
		(property "Value" ""
			(at 0 0 0)
			(layer "F.Fab")
			(effects
				(font
					(size 1.27 1.27)
				)
			)
		)
		(duplicate_pad_numbers_are_jumpers no)
		(fp_line
			(start -0.7874 -0.4064)
			(end 0.7874 -0.4064)
			(stroke
				(width 0.1524)
				(type default)
			)
			(layer "F.SilkS")
		)
		(fp_line
			(start -0.7874 0.4064)
			(end -0.7874 -0.4064)
			(stroke
				(width 0.1524)
				(type default)
			)
			(layer "F.SilkS")
		)
		(fp_line
			(start 0.7874 -0.4064)
			(end 0.7874 0.4064)
			(stroke
				(width 0.1524)
				(type default)
			)
			(layer "F.SilkS")
		)
		(fp_line
			(start 0.7874 0.4064)
			(end -0.7874 0.4064)
			(stroke
				(width 0.1524)
				(type default)
			)
			(layer "F.SilkS")
		)
		(fp_line
			(start -0.67945 -0.305054)
			(end -0.12065 -0.305054)
			(stroke
				(width 0.1)
				(type default)
			)
			(layer "F.Fab")
		)
		(fp_line
			(start -0.67945 0.3048)
			(end -0.67945 -0.305054)
			(stroke
				(width 0.1)
				(type default)
			)
			(layer "F.Fab")
		)
		(fp_line
			(start -0.12065 -0.305054)
			(end -0.12065 -0.2794)
			(stroke
				(width 0.1)
				(type default)
			)
			(layer "F.Fab")
		)
		(fp_line
			(start -0.12065 -0.2794)
			(end 0.12065 -0.2794)
			(stroke
				(width 0.1)
				(type default)
			)
			(layer "F.Fab")
		)
		(fp_line
			(start -0.12065 0.2794)
			(end -0.12065 0.3048)
			(stroke
				(width 0.1)
				(type default)
			)
			(layer "F.Fab")
		)
		(fp_line
			(start -0.12065 0.3048)
			(end -0.67945 0.3048)
			(stroke
				(width 0.1)
				(type default)
			)
			(layer "F.Fab")
		)
		(fp_line
			(start 0.120396 0.2794)
			(end -0.12065 0.2794)
			(stroke
				(width 0.1)
				(type default)
			)
			(layer "F.Fab")
		)
		(fp_line
			(start 0.120396 0.3048)
			(end 0.120396 0.2794)
			(stroke
				(width 0.1)
				(type default)
			)
			(layer "F.Fab")
		)
		(fp_line
			(start 0.12065 -0.3048)
			(end 0.67945 -0.3048)
			(stroke
				(width 0.1)
				(type default)
			)
			(layer "F.Fab")
		)
		(fp_line
			(start 0.12065 -0.2794)
			(end 0.12065 -0.3048)
			(stroke
				(width 0.1)
				(type default)
			)
			(layer "F.Fab")
		)
		(fp_line
			(start 0.67945 -0.3048)
			(end 0.67945 0.3048)
			(stroke
				(width 0.1)
				(type default)
			)
			(layer "F.Fab")
		)
		(fp_line
			(start 0.67945 0.3048)
			(end 0.120396 0.3048)
			(stroke
				(width 0.1)
				(type default)
			)
			(layer "F.Fab")
		)
		(pad "1" smd circle
			(at -0.40005 0)
			(size 0 0)
			(layers "F.Cu" "F.Mask" "F.Paste")
			(net "PVDDCR_CPU1_P1_LSET3")
		)
		(pad "2" smd circle
			(at 0.40005 0)
			(size 0 0)
			(layers "F.Cu" "F.Mask" "F.Paste")
			(net "GND")
		)
	)
	(footprint ""
		(layer "F.Cu")
		(at 363.217206 -261.747762 -90)
		(property "Reference" "C2641"
			(at 0 0 270)
			(layer "F.SilkS")
			(hide yes)
			(effects
				(font
					(size 1.27 1.27)
				)
			)
		)
		(property "Value" ""
			(at 0 0 270)
			(layer "F.Fab")
			(effects
				(font
					(size 1.27 1.27)
				)
			)
		)
		(duplicate_pad_numbers_are_jumpers no)
		(fp_line
			(start -0.7874 0.4064)
			(end -0.7874 -0.4064)
			(stroke
				(width 0.1524)
				(type default)
			)
			(layer "F.SilkS")
		)
		(fp_line
			(start 0.7874 0.4064)
			(end -0.7874 0.4064)
			(stroke
				(width 0.1524)
				(type default)
			)
			(layer "F.SilkS")
		)
		(fp_line
			(start -0.7874 -0.4064)
			(end 0.7874 -0.4064)
			(stroke
				(width 0.1524)
				(type default)
			)
			(layer "F.SilkS")
		)
		(fp_line
			(start 0.7874 -0.4064)
			(end 0.7874 0.4064)
			(stroke
				(width 0.1524)
				(type default)
			)
			(layer "F.SilkS")
		)
		(fp_line
			(start -0.67945 0.3048)
			(end -0.67945 -0.305054)
			(stroke
				(width 0.1)
				(type default)
			)
			(layer "F.Fab")
		)
		(fp_line
			(start -0.12065 0.3048)
			(end -0.67945 0.3048)
			(stroke
				(width 0.1)
				(type default)
			)
			(layer "F.Fab")
		)
		(fp_line
			(start 0.120396 0.3048)
			(end 0.120396 0.2794)
			(stroke
				(width 0.1)
				(type default)
			)
			(layer "F.Fab")
		)
		(fp_line
			(start 0.67945 0.3048)
			(end 0.120396 0.3048)
			(stroke
				(width 0.1)
				(type default)
			)
			(layer "F.Fab")
		)
		(fp_line
			(start -0.12065 0.2794)
			(end -0.12065 0.3048)
			(stroke
				(width 0.1)
				(type default)
			)
			(layer "F.Fab")
		)
		(fp_line
			(start 0.120396 0.2794)
			(end -0.12065 0.2794)
			(stroke
				(width 0.1)
				(type default)
			)
			(layer "F.Fab")
		)
		(fp_line
			(start -0.12065 -0.2794)
			(end 0.12065 -0.2794)
			(stroke
				(width 0.1)
				(type default)
			)
			(layer "F.Fab")
		)
		(fp_line
			(start 0.12065 -0.2794)
			(end 0.12065 -0.3048)
			(stroke
				(width 0.1)
				(type default)
			)
			(layer "F.Fab")
		)
		(fp_line
			(start 0.12065 -0.3048)
			(end 0.67945 -0.3048)
			(stroke
				(width 0.1)
				(type default)
			)
			(layer "F.Fab")
		)
		(fp_line
			(start 0.67945 -0.3048)
			(end 0.67945 0.3048)
			(stroke
				(width 0.1)
				(type default)
			)
			(layer "F.Fab")
		)
		(fp_line
			(start -0.67945 -0.305054)
			(end -0.12065 -0.305054)
			(stroke
				(width 0.1)
				(type default)
			)
			(layer "F.Fab")
		)
		(fp_line
			(start -0.12065 -0.305054)
			(end -0.12065 -0.2794)
			(stroke
				(width 0.1)
				(type default)
			)
			(layer "F.Fab")
		)
		(pad "1" smd circle
			(at -0.40005 0 270)
			(size 0 0)
			(layers "F.Cu" "F.Mask" "F.Paste")
			(net "PVDD11_S3_P0")
		)
		(pad "2" smd circle
			(at 0.40005 0 270)
			(size 0 0)
			(layers "F.Cu" "F.Mask" "F.Paste")
			(net "GND")
		)
	)
	(footprint ""
		(layer "F.Cu")
		(at 418.25164 -383.88163 -90)
		(property "Reference" "C848"
			(at 0 0 270)
			(layer "F.SilkS")
			(hide yes)
			(effects
				(font
					(size 1.27 1.27)
				)
			)
		)
		(property "Value" ""
			(at 0 0 270)
			(layer "F.Fab")
			(effects
				(font
					(size 1.27 1.27)
				)
			)
		)
		(duplicate_pad_numbers_are_jumpers no)
		(fp_line
			(start -0.299974 0.150114)
			(end -0.299974 -0.150114)
			(stroke
				(width 0.1)
				(type default)
			)
			(layer "F.Fab")
		)
		(fp_line
			(start 0.299974 0.150114)
			(end -0.299974 0.150114)
			(stroke
				(width 0.1)
				(type default)
			)
			(layer "F.Fab")
		)
		(fp_line
			(start -0.299974 -0.150114)
			(end 0.299974 -0.150114)
			(stroke
				(width 0.1)
				(type default)
			)
			(layer "F.Fab")
		)
		(fp_line
			(start 0.299974 -0.150114)
			(end 0.299974 0.150114)
			(stroke
				(width 0.1)
				(type default)
			)
			(layer "F.Fab")
		)
		(pad "1" smd rect
			(at -0.2667 0 270)
			(size 0.3048 0.381)
			(layers "F.Cu" "F.Mask" "F.Paste")
			(net "P5E_CPU0_P2_TX_C_DN<10>")
		)
		(pad "2" smd rect
			(at 0.2667 0 270)
			(size 0.3048 0.381)
			(layers "F.Cu" "F.Mask" "F.Paste")
			(net "P5E_CPU0_P2_TX_DN<10>")
		)
	)
)
